(kicad_pcb
	(version 20260206)
	(generator "pcbnew")
	(generator_version "10.0")
	(general
		(thickness 1.6)
		(legacy_teardrops no)
	)
	(paper "A4")
	(title_block
		(title "Bryce Canyon_SCC_16316-1_OCP.brd")
		(comment 1 "Bryce Canyon / footprints 1266-1273 of 1561")
	)
	(layers
		(0 "F.Cu" signal "TOP")
		(4 "In1.Cu" signal "L2GND")
		(6 "In2.Cu" signal "L3")
		(8 "In3.Cu" signal "L4VCC")
		(10 "In4.Cu" signal "L5VCC")
		(12 "In5.Cu" signal "L6")
		(14 "In6.Cu" signal "L7GND")
		(2 "B.Cu" signal "BOTTOM")
		(9 "F.Adhes" user "F.Adhesive")
		(11 "B.Adhes" user "B.Adhesive")
		(13 "F.Paste" user "Package Geometry/Pastemask Top")
		(15 "B.Paste" user "Package Geometry/Pastemask Bottom")
		(5 "F.SilkS" user "Ref Des/Silkscreen Top")
		(7 "B.SilkS" user "Ref Des/Silkscreen Bottom")
		(1 "F.Mask" user "Board Geometry/Soldermask Top")
		(3 "B.Mask" user "Board Geometry/Soldermask Bottom")
		(17 "Dwgs.User" user "User.Drawings")
		(19 "Cmts.User" user "User.Comments")
		(21 "Eco1.User" user "User.Eco1")
		(23 "Eco2.User" user "User.Eco2")
		(25 "Edge.Cuts" user "Board Geometry/Outline")
		(27 "Margin" user)
		(31 "F.CrtYd" user "Package Geometry/Place Bound Top")
		(29 "B.CrtYd" user "Package Geometry/Place Bound Bottom")
		(35 "F.Fab" user "Ref Des/Assembly Top")
		(33 "B.Fab" user "Ref Des/Assembly Bottom")
	)
	(footprint ""
		(layer "B.Cu")
		(at 164.592 -52.07)
		(property "Reference" "R197"
			(at 0 0 0)
			(layer "B.SilkS")
			(hide yes)
			(effects
				(font
					(size 1.27 1.27)
				)
				(justify mirror)
			)
		)
		(property "Value" "2K2R2F-GP"
			(at -0.064008 -3.993896 0)
			(unlocked yes)
			(layer "B.Fab")
			(hide yes)
			(effects
				(font
					(size 1.016 1.016)
					(thickness 0.1524)
				)
				(justify mirror)
			)
		)
		(property "Device Type" "R402H16"
			(at -0.064008 -5.517896 0)
			(unlocked yes)
			(layer "B.Fab")
			(hide yes)
			(effects
				(font
					(size 1.016 1.016)
					(thickness 0.1524)
				)
				(justify mirror)
			)
		)
		(duplicate_pad_numbers_are_jumpers no)
		(fp_line
			(start -0.508 -0.9398)
			(end 0.508 -0.9398)
			(stroke
				(width 0.1524)
				(type default)
			)
			(layer "B.SilkS")
		)
		(fp_line
			(start 0.508 -0.9398)
			(end 0.508 0.9398)
			(stroke
				(width 0.1524)
				(type default)
			)
			(layer "B.SilkS")
		)
		(fp_rect
			(start 0.508 0.9398)
			(end -0.508 -0.9398)
			(stroke
				(width 0)
				(type default)
			)
			(fill no)
			(layer "B.CrtYd")
		)
		(fp_rect
			(start 0.508 0.9398)
			(end -0.508 -0.9398)
			(stroke
				(width 0)
				(type default)
			)
			(fill no)
			(layer "B.Fab")
		)
		(pad "1" smd custom
			(at 0 -0.4445 180)
			(size 0.1397 0.1397)
			(layers "B.Cu" "B.Mask" "B.Paste")
			(net "P1V8_C")
			(options
				(clearance outline)
				(anchor circle)
			)
			(primitives
				(gr_poly
					(pts
						(arc
							(start -0.1778 0.2794)
							(mid -0.249642 0.249642)
							(end -0.2794 0.1778)
						)
						(arc
							(start -0.2794 -0.1778)
							(mid -0.249642 -0.249642)
							(end -0.1778 -0.2794)
						)
						(arc
							(start 0.1778 -0.2794)
							(mid 0.249642 -0.249642)
							(end 0.2794 -0.1778)
						)
						(arc
							(start 0.2794 0.1778)
							(mid 0.249642 0.249642)
							(end 0.1778 0.2794)
						)
					)
					(width 0)
					(fill yes)
				)
			)
		)
		(pad "2" smd custom
			(at 0 0.4445 180)
			(size 0.1397 0.1397)
			(layers "B.Cu" "B.Mask" "B.Paste")
			(net "SIO_DIN_1")
			(options
				(clearance outline)
				(anchor circle)
			)
			(primitives
				(gr_poly
					(pts
						(arc
							(start -0.1778 0.2794)
							(mid -0.249642 0.249642)
							(end -0.2794 0.1778)
						)
						(arc
							(start -0.2794 -0.1778)
							(mid -0.249642 -0.249642)
							(end -0.1778 -0.2794)
						)
						(arc
							(start 0.1778 -0.2794)
							(mid 0.249642 -0.249642)
							(end 0.2794 -0.1778)
						)
						(arc
							(start 0.2794 0.1778)
							(mid 0.249642 0.249642)
							(end 0.1778 0.2794)
						)
					)
					(width 0)
					(fill yes)
				)
			)
		)
	)
	(footprint ""
		(layer "B.Cu")
		(at 175.524414 -48.189642 -90)
		(property "Reference" "C488"
			(at 0 0 90)
			(layer "B.SilkS")
			(hide yes)
			(effects
				(font
					(size 1.27 1.27)
				)
				(justify mirror)
			)
		)
		(property "Value" "SCD1U6D3V1KX-GP"
			(at 2.8321 -1.7399 270)
			(unlocked yes)
			(layer "B.Fab")
			(hide yes)
			(effects
				(font
					(size 1.016 1.016)
					(thickness 0.1524)
				)
				(justify mirror)
			)
		)
		(property "Device Type" "C0201H13"
			(at 2.8321 -3.2639 270)
			(unlocked yes)
			(layer "B.Fab")
			(hide yes)
			(effects
				(font
					(size 1.016 1.016)
					(thickness 0.1524)
				)
				(justify mirror)
			)
		)
		(duplicate_pad_numbers_are_jumpers no)
		(fp_rect
			(start 0.2794 0.6477)
			(end -0.2794 -0.6477)
			(stroke
				(width 0)
				(type default)
			)
			(fill no)
			(layer "B.CrtYd")
		)
		(fp_rect
			(start 0.2794 0.6477)
			(end -0.2794 -0.6477)
			(stroke
				(width 0)
				(type default)
			)
			(fill no)
			(layer "B.Fab")
		)
		(pad "1" smd custom
			(at 0 -0.2794 90)
			(size 0.0762 0.0762)
			(layers "B.Cu" "B.Mask" "B.Paste")
			(net "P1V8_C")
			(options
				(clearance outline)
				(anchor circle)
			)
			(primitives
				(gr_poly
					(pts
						(arc
							(start 0.1524 0.127)
							(mid 0.137521 0.162921)
							(end 0.1016 0.1778)
						)
						(arc
							(start -0.1016 0.1778)
							(mid -0.137521 0.162921)
							(end -0.1524 0.127)
						)
						(arc
							(start -0.1524 -0.127)
							(mid -0.137521 -0.162921)
							(end -0.1016 -0.1778)
						)
						(arc
							(start 0.1016 -0.1778)
							(mid 0.137521 -0.162921)
							(end 0.1524 -0.127)
						)
					)
					(width 0)
					(fill yes)
				)
			)
		)
		(pad "2" smd custom
			(at 0 0.2794 90)
			(size 0.0762 0.0762)
			(layers "B.Cu" "B.Mask" "B.Paste")
			(net "GND")
			(options
				(clearance outline)
				(anchor circle)
			)
			(primitives
				(gr_poly
					(pts
						(arc
							(start 0.1524 0.127)
							(mid 0.137521 0.162921)
							(end 0.1016 0.1778)
						)
						(arc
							(start -0.1016 0.1778)
							(mid -0.137521 0.162921)
							(end -0.1524 0.127)
						)
						(arc
							(start -0.1524 -0.127)
							(mid -0.137521 -0.162921)
							(end -0.1016 -0.1778)
						)
						(arc
							(start 0.1016 -0.1778)
							(mid 0.137521 -0.162921)
							(end 0.1524 -0.127)
						)
					)
					(width 0)
					(fill yes)
				)
			)
		)
	)
	(footprint ""
		(layer "B.Cu")
		(at 106.499914 -78.49997)
		(property "Reference" "TP43"
			(at 0 0 0)
			(layer "B.SilkS")
			(hide yes)
			(effects
				(font
					(size 1.27 1.27)
				)
				(justify mirror)
			)
		)
		(property "Value" "TPAD28-2-GP"
			(at 0.0127 -1.6637 0)
			(unlocked yes)
			(layer "B.Fab")
			(hide yes)
			(effects
				(font
					(size 1.016 1.016)
					(thickness 0.1524)
				)
				(justify mirror)
			)
		)
		(property "Device Type" "TPAD28"
			(at 0.0127 -3.1877 0)
			(unlocked yes)
			(layer "B.Fab")
			(hide yes)
			(effects
				(font
					(size 1.016 1.016)
					(thickness 0.1524)
				)
				(justify mirror)
			)
		)
		(duplicate_pad_numbers_are_jumpers no)
		(fp_poly
			(pts
				(arc
					(start 0.3556 0)
					(mid -0.3556 0)
					(end 0.3556 0)
				)
			)
			(stroke
				(width 0)
				(type default)
			)
			(fill no)
			(layer "B.CrtYd")
		)
		(fp_poly
			(pts
				(arc
					(start 0.6096 0)
					(mid -0.6096 0)
					(end 0.6096 0)
				)
			)
			(stroke
				(width 0)
				(type default)
			)
			(fill no)
			(layer "B.Fab")
		)
		(pad "1" smd circle
			(at 0 0 180)
			(size 0.7112 0.7112)
			(layers "B.Cu" "B.Mask" "B.Paste")
			(net "TESTIBIAS")
		)
	)
	(footprint ""
		(layer "B.Cu")
		(at 177.8127 -38.66896 90)
		(property "Reference" "C413"
			(at 0 0 90)
			(layer "B.SilkS")
			(hide yes)
			(effects
				(font
					(size 1.27 1.27)
				)
				(justify mirror)
			)
		)
		(property "Value" "SC1U6D3V1MX-GP"
			(at -1.9177 2.0193 90)
			(unlocked yes)
			(layer "B.Fab")
			(hide yes)
			(effects
				(font
					(size 1.016 1.016)
					(thickness 0.1524)
				)
				(justify mirror)
			)
		)
		(property "Device Type" "C0201H14"
			(at -1.9177 0.4953 90)
			(unlocked yes)
			(layer "B.Fab")
			(hide yes)
			(effects
				(font
					(size 1.016 1.016)
					(thickness 0.1524)
				)
				(justify mirror)
			)
		)
		(duplicate_pad_numbers_are_jumpers no)
		(fp_rect
			(start 0.1524 0.3048)
			(end -0.1524 -0.3048)
			(stroke
				(width 0)
				(type default)
			)
			(fill no)
			(layer "B.CrtYd")
		)
		(fp_poly
			(pts
				(xy 0.2794 0.6477) (xy 0.2794 -0.6477) (xy -0.2794 -0.6477) (xy -0.2794 -0.1905) (xy -0.1524 -0.1905)
				(xy -0.1524 -0.3048) (xy 0.1524 -0.3048) (xy 0.1524 0.3048) (xy -0.1524 0.3048) (xy -0.1524 -0.1778)
				(xy -0.2794 -0.1778) (xy -0.2794 0.6477)
			)
			(stroke
				(width 0)
				(type default)
			)
			(fill no)
			(layer "B.CrtYd")
		)
		(fp_rect
			(start 0.2794 0.6477)
			(end -0.2794 -0.6477)
			(stroke
				(width 0)
				(type default)
			)
			(fill no)
			(layer "B.Fab")
		)
		(pad "1" smd custom
			(at 0 -0.2794 270)
			(size 0.0762 0.0762)
			(layers "B.Cu" "B.Mask" "B.Paste")
			(net "P0V975")
			(options
				(clearance outline)
				(anchor circle)
			)
			(primitives
				(gr_poly
					(pts
						(arc
							(start 0.1524 0.127)
							(mid 0.137521 0.162921)
							(end 0.1016 0.1778)
						)
						(arc
							(start -0.1016 0.1778)
							(mid -0.137521 0.162921)
							(end -0.1524 0.127)
						)
						(arc
							(start -0.1524 -0.127)
							(mid -0.137521 -0.162921)
							(end -0.1016 -0.1778)
						)
						(arc
							(start 0.1016 -0.1778)
							(mid 0.137521 -0.162921)
							(end 0.1524 -0.127)
						)
					)
					(width 0)
					(fill yes)
				)
			)
		)
		(pad "2" smd custom
			(at 0 0.2794 270)
			(size 0.0762 0.0762)
			(layers "B.Cu" "B.Mask" "B.Paste")
			(net "GND")
			(options
				(clearance outline)
				(anchor circle)
			)
			(primitives
				(gr_poly
					(pts
						(arc
							(start 0.1524 0.127)
							(mid 0.137521 0.162921)
							(end 0.1016 0.1778)
						)
						(arc
							(start -0.1016 0.1778)
							(mid -0.137521 0.162921)
							(end -0.1524 0.127)
						)
						(arc
							(start -0.1524 -0.127)
							(mid -0.137521 -0.162921)
							(end -0.1016 -0.1778)
						)
						(arc
							(start 0.1016 -0.1778)
							(mid 0.137521 -0.162921)
							(end 0.1524 -0.127)
						)
					)
					(width 0)
					(fill yes)
				)
			)
		)
	)
	(footprint ""
		(layer "B.Cu")
		(at 70.485 -46.482 90)
		(property "Reference" "R167"
			(at 0 0 90)
			(layer "B.SilkS")
			(hide yes)
			(effects
				(font
					(size 1.27 1.27)
				)
				(justify mirror)
			)
		)
		(property "Value" "D51R3F-2-GP"
			(at 0.0254 -2.5146 90)
			(unlocked yes)
			(layer "B.Fab")
			(hide yes)
			(effects
				(font
					(size 1.016 1.016)
					(thickness 0.1524)
				)
				(justify mirror)
			)
		)
		(property "Device Type" "R603H22"
			(at 0.0254 -4.0386 90)
			(unlocked yes)
			(layer "B.Fab")
			(hide yes)
			(effects
				(font
					(size 1.016 1.016)
					(thickness 0.1524)
				)
				(justify mirror)
			)
		)
		(duplicate_pad_numbers_are_jumpers no)
		(fp_line
			(start 0.4826 0)
			(end 0.2032 0)
			(stroke
				(width 0.2032)
				(type default)
			)
			(layer "B.SilkS")
		)
		(fp_line
			(start -0.2032 0)
			(end -0.4826 0)
			(stroke
				(width 0.2032)
				(type default)
			)
			(layer "B.SilkS")
		)
		(fp_rect
			(start 0.5842 1.3335)
			(end -0.5842 -1.3335)
			(stroke
				(width 0)
				(type default)
			)
			(fill no)
			(layer "B.CrtYd")
		)
		(fp_rect
			(start 0.5842 1.3335)
			(end -0.5842 -1.3335)
			(stroke
				(width 0)
				(type default)
			)
			(fill no)
			(layer "B.Fab")
		)
		(pad "1" smd custom
			(at 0 -0.762 270)
			(size 0.2159 0.2159)
			(layers "B.Cu" "B.Mask" "B.Paste")
			(net "P0V9")
			(options
				(clearance outline)
				(anchor circle)
			)
			(primitives
				(gr_poly
					(pts
						(arc
							(start -0.3302 0.4318)
							(mid -0.402042 0.402042)
							(end -0.4318 0.3302)
						)
						(arc
							(start -0.4318 -0.3302)
							(mid -0.402042 -0.402042)
							(end -0.3302 -0.4318)
						)
						(arc
							(start 0.3302 -0.4318)
							(mid 0.402042 -0.402042)
							(end 0.4318 -0.3302)
						)
						(arc
							(start 0.4318 0.3302)
							(mid 0.402042 0.402042)
							(end 0.3302 0.4318)
						)
					)
					(width 0)
					(fill yes)
				)
			)
		)
		(pad "2" smd custom
			(at 0 0.762 270)
			(size 0.2159 0.2159)
			(layers "B.Cu" "B.Mask" "B.Paste")
			(net "GB_VDDA")
			(options
				(clearance outline)
				(anchor circle)
			)
			(primitives
				(gr_poly
					(pts
						(arc
							(start -0.3302 0.4318)
							(mid -0.402042 0.402042)
							(end -0.4318 0.3302)
						)
						(arc
							(start -0.4318 -0.3302)
							(mid -0.402042 -0.402042)
							(end -0.3302 -0.4318)
						)
						(arc
							(start 0.3302 -0.4318)
							(mid 0.402042 -0.402042)
							(end 0.4318 -0.3302)
						)
						(arc
							(start 0.4318 0.3302)
							(mid 0.402042 0.402042)
							(end 0.3302 0.4318)
						)
					)
					(width 0)
					(fill yes)
				)
			)
		)
	)
	(footprint ""
		(layer "B.Cu")
		(at 107.517438 -65.786 180)
		(property "Reference" "C206"
			(at 0 0 0)
			(layer "B.SilkS")
			(hide yes)
			(effects
				(font
					(size 1.27 1.27)
				)
				(justify mirror)
			)
		)
		(property "Value" "SC1U6D3V1MX-GP"
			(at -1.9177 2.0193 180)
			(unlocked yes)
			(layer "B.Fab")
			(hide yes)
			(effects
				(font
					(size 1.016 1.016)
					(thickness 0.1524)
				)
				(justify mirror)
			)
		)
		(property "Device Type" "C0201H14"
			(at -1.9177 0.4953 180)
			(unlocked yes)
			(layer "B.Fab")
			(hide yes)
			(effects
				(font
					(size 1.016 1.016)
					(thickness 0.1524)
				)
				(justify mirror)
			)
		)
		(duplicate_pad_numbers_are_jumpers no)
		(fp_rect
			(start 0.1524 0.3048)
			(end -0.1524 -0.3048)
			(stroke
				(width 0)
				(type default)
			)
			(fill no)
			(layer "B.CrtYd")
		)
		(fp_poly
			(pts
				(xy 0.2794 0.6477) (xy 0.2794 -0.6477) (xy -0.2794 -0.6477) (xy -0.2794 -0.1905) (xy -0.1524 -0.1905)
				(xy -0.1524 -0.3048) (xy 0.1524 -0.3048) (xy 0.1524 0.3048) (xy -0.1524 0.3048) (xy -0.1524 -0.1778)
				(xy -0.2794 -0.1778) (xy -0.2794 0.6477)
			)
			(stroke
				(width 0)
				(type default)
			)
			(fill no)
			(layer "B.CrtYd")
		)
		(fp_rect
			(start 0.2794 0.6477)
			(end -0.2794 -0.6477)
			(stroke
				(width 0)
				(type default)
			)
			(fill no)
			(layer "B.Fab")
		)
		(pad "1" smd custom
			(at 0 -0.2794)
			(size 0.0762 0.0762)
			(layers "B.Cu" "B.Mask" "B.Paste")
			(net "XTAL_VDDA09")
			(options
				(clearance outline)
				(anchor circle)
			)
			(primitives
				(gr_poly
					(pts
						(arc
							(start 0.1524 0.127)
							(mid 0.137521 0.162921)
							(end 0.1016 0.1778)
						)
						(arc
							(start -0.1016 0.1778)
							(mid -0.137521 0.162921)
							(end -0.1524 0.127)
						)
						(arc
							(start -0.1524 -0.127)
							(mid -0.137521 -0.162921)
							(end -0.1016 -0.1778)
						)
						(arc
							(start 0.1016 -0.1778)
							(mid 0.137521 -0.162921)
							(end 0.1524 -0.127)
						)
					)
					(width 0)
					(fill yes)
				)
			)
		)
		(pad "2" smd custom
			(at 0 0.2794)
			(size 0.0762 0.0762)
			(layers "B.Cu" "B.Mask" "B.Paste")
			(net "GND")
			(options
				(clearance outline)
				(anchor circle)
			)
			(primitives
				(gr_poly
					(pts
						(arc
							(start 0.1524 0.127)
							(mid 0.137521 0.162921)
							(end 0.1016 0.1778)
						)
						(arc
							(start -0.1016 0.1778)
							(mid -0.137521 0.162921)
							(end -0.1524 0.127)
						)
						(arc
							(start -0.1524 -0.127)
							(mid -0.137521 -0.162921)
							(end -0.1016 -0.1778)
						)
						(arc
							(start 0.1016 -0.1778)
							(mid 0.137521 -0.162921)
							(end 0.1524 -0.127)
						)
					)
					(width 0)
					(fill yes)
				)
			)
		)
	)
	(footprint ""
		(layer "B.Cu")
		(at 146.2532 -123.9266 -90)
		(property "Reference" "R601"
			(at 0 0 90)
			(layer "B.SilkS")
			(hide yes)
			(effects
				(font
					(size 1.27 1.27)
				)
				(justify mirror)
			)
		)
		(property "Value" "0R2J-2-GP"
			(at -0.064008 -3.993896 270)
			(unlocked yes)
			(layer "B.Fab")
			(hide yes)
			(effects
				(font
					(size 1.016 1.016)
					(thickness 0.1524)
				)
				(justify mirror)
			)
		)
		(property "Device Type" "R402H16"
			(at -0.064008 -5.517896 270)
			(unlocked yes)
			(layer "B.Fab")
			(hide yes)
			(effects
				(font
					(size 1.016 1.016)
					(thickness 0.1524)
				)
				(justify mirror)
			)
		)
		(duplicate_pad_numbers_are_jumpers no)
		(fp_line
			(start -0.508 -0.9398)
			(end 0.508 -0.9398)
			(stroke
				(width 0.1524)
				(type default)
			)
			(layer "B.SilkS")
		)
		(fp_line
			(start 0.508 -0.9398)
			(end 0.508 0.9398)
			(stroke
				(width 0.1524)
				(type default)
			)
			(layer "B.SilkS")
		)
		(fp_rect
			(start 0.508 0.9398)
			(end -0.508 -0.9398)
			(stroke
				(width 0)
				(type default)
			)
			(fill no)
			(layer "B.CrtYd")
		)
		(fp_rect
			(start 0.508 0.9398)
			(end -0.508 -0.9398)
			(stroke
				(width 0)
				(type default)
			)
			(fill no)
			(layer "B.Fab")
		)
		(pad "1" smd custom
			(at 0 -0.4445 90)
			(size 0.1397 0.1397)
			(layers "B.Cu" "B.Mask" "B.Paste")
			(net "P1V5_C_PG")
			(options
				(clearance outline)
				(anchor circle)
			)
			(primitives
				(gr_poly
					(pts
						(arc
							(start -0.1778 0.2794)
							(mid -0.249642 0.249642)
							(end -0.2794 0.1778)
						)
						(arc
							(start -0.2794 -0.1778)
							(mid -0.249642 -0.249642)
							(end -0.1778 -0.2794)
						)
						(arc
							(start 0.1778 -0.2794)
							(mid 0.249642 -0.249642)
							(end 0.2794 -0.1778)
						)
						(arc
							(start 0.2794 0.1778)
							(mid 0.249642 0.249642)
							(end 0.1778 0.2794)
						)
					)
					(width 0)
					(fill yes)
				)
			)
		)
		(pad "2" smd custom
			(at 0 0.4445 90)
			(size 0.1397 0.1397)
			(layers "B.Cu" "B.Mask" "B.Paste")
			(net "P1V5_C_PG_R_1")
			(options
				(clearance outline)
				(anchor circle)
			)
			(primitives
				(gr_poly
					(pts
						(arc
							(start -0.1778 0.2794)
							(mid -0.249642 0.249642)
							(end -0.2794 0.1778)
						)
						(arc
							(start -0.2794 -0.1778)
							(mid -0.249642 -0.249642)
							(end -0.1778 -0.2794)
						)
						(arc
							(start 0.1778 -0.2794)
							(mid 0.249642 -0.249642)
							(end 0.2794 -0.1778)
						)
						(arc
							(start 0.2794 0.1778)
							(mid 0.249642 0.249642)
							(end 0.1778 0.2794)
						)
					)
					(width 0)
					(fill yes)
				)
			)
		)
	)
	(footprint ""
		(layer "B.Cu")
		(at 119.4054 -59.4487)
		(property "Reference" "C291"
			(at 0 0 0)
			(layer "B.SilkS")
			(hide yes)
			(effects
				(font
					(size 1.27 1.27)
				)
				(justify mirror)
			)
		)
		(property "Value" "SCD1U6D3V1KX-GP"
			(at 2.8321 -1.7399 0)
			(unlocked yes)
			(layer "B.Fab")
			(hide yes)
			(effects
				(font
					(size 1.016 1.016)
					(thickness 0.1524)
				)
				(justify mirror)
			)
		)
		(property "Device Type" "C0201H13"
			(at 2.8321 -3.2639 0)
			(unlocked yes)
			(layer "B.Fab")
			(hide yes)
			(effects
				(font
					(size 1.016 1.016)
					(thickness 0.1524)
				)
				(justify mirror)
			)
		)
		(duplicate_pad_numbers_are_jumpers no)
		(fp_rect
			(start 0.2794 0.6477)
			(end -0.2794 -0.6477)
			(stroke
				(width 0)
				(type default)
			)
			(fill no)
			(layer "B.CrtYd")
		)
		(fp_rect
			(start 0.2794 0.6477)
			(end -0.2794 -0.6477)
			(stroke
				(width 0)
				(type default)
			)
			(fill no)
			(layer "B.Fab")
		)
		(pad "1" smd custom
			(at 0 -0.2794 180)
			(size 0.0762 0.0762)
			(layers "B.Cu" "B.Mask" "B.Paste")
			(net "GB_VDDA")
			(options
				(clearance outline)
				(anchor circle)
			)
			(primitives
				(gr_poly
					(pts
						(arc
							(start 0.1524 0.127)
							(mid 0.137521 0.162921)
							(end 0.1016 0.1778)
						)
						(arc
							(start -0.1016 0.1778)
							(mid -0.137521 0.162921)
							(end -0.1524 0.127)
						)
						(arc
							(start -0.1524 -0.127)
							(mid -0.137521 -0.162921)
							(end -0.1016 -0.1778)
						)
						(arc
							(start 0.1016 -0.1778)
							(mid 0.137521 -0.162921)
							(end 0.1524 -0.127)
						)
					)
					(width 0)
					(fill yes)
				)
			)
		)
		(pad "2" smd custom
			(at 0 0.2794 180)
			(size 0.0762 0.0762)
			(layers "B.Cu" "B.Mask" "B.Paste")
			(net "GND")
			(options
				(clearance outline)
				(anchor circle)
			)
			(primitives
				(gr_poly
					(pts
						(arc
							(start 0.1524 0.127)
							(mid 0.137521 0.162921)
							(end 0.1016 0.1778)
						)
						(arc
							(start -0.1016 0.1778)
							(mid -0.137521 0.162921)
							(end -0.1524 0.127)
						)
						(arc
							(start -0.1524 -0.127)
							(mid -0.137521 -0.162921)
							(end -0.1016 -0.1778)
						)
						(arc
							(start 0.1016 -0.1778)
							(mid 0.137521 -0.162921)
							(end 0.1524 -0.127)
						)
					)
					(width 0)
					(fill yes)
				)
			)
		)
	)
)
